(kicad_pcb
	(version 20260206)
	(generator "pcbnew")
	(generator_version "10.0")
	(general
		(thickness 1.6)
		(legacy_teardrops no)
	)
	(paper "A4")
	(title_block
		(title "baseboard — 13948-1b.1110WZS1818.brd")
		(comment 1 "Honey Badger (Wiwynn) / footprints 1905-1913 of 2523")
	)
	(layers
		(0 "F.Cu" signal "TOP")
		(4 "In1.Cu" signal "L2GND")
		(6 "In2.Cu" signal "L3")
		(8 "In3.Cu" signal "L4VCC")
		(10 "In4.Cu" signal "L5VCC")
		(12 "In5.Cu" signal "L6")
		(14 "In6.Cu" signal "L7GND")
		(2 "B.Cu" signal "BOTTOM")
		(9 "F.Adhes" user "F.Adhesive")
		(11 "B.Adhes" user "B.Adhesive")
		(13 "F.Paste" user "Package Geometry/Pastemask Top")
		(15 "B.Paste" user "Package Geometry/Pastemask Bottom")
		(5 "F.SilkS" user "Ref Des/Silkscreen Top")
		(7 "B.SilkS" user "Ref Des/Silkscreen Bottom")
		(1 "F.Mask" user "Board Geometry/Soldermask Top")
		(3 "B.Mask" user "Board Geometry/Soldermask Bottom")
		(17 "Dwgs.User" user "User.Drawings")
		(19 "Cmts.User" user "User.Comments")
		(21 "Eco1.User" user "User.Eco1")
		(23 "Eco2.User" user "User.Eco2")
		(25 "Edge.Cuts" user "Board Geometry/Outline")
		(27 "Margin" user)
		(31 "F.CrtYd" user "Package Geometry/Place Bound Top")
		(29 "B.CrtYd" user "Package Geometry/Place Bound Bottom")
		(35 "F.Fab" user "Ref Des/Assembly Top")
		(33 "B.Fab" user "Ref Des/Assembly Bottom")
	)
	(footprint ""
		(layer "B.Cu")
		(at 122.727212 -218.821)
		(property "Reference" "STP143"
			(at 0 0 0)
			(layer "B.SilkS")
			(hide yes)
			(effects
				(font
					(size 1.27 1.27)
				)
				(justify mirror)
			)
		)
		(property "Value" "TPAD32-GP"
			(at 0 -3.166364 0)
			(unlocked yes)
			(layer "B.Fab")
			(hide yes)
			(effects
				(font
					(size 1.016 1.016)
					(thickness 0.1524)
				)
				(justify mirror)
			)
		)
		(property "Device Type" "TPAD32"
			(at 0 -4.690618 0)
			(unlocked yes)
			(layer "B.Fab")
			(hide yes)
			(effects
				(font
					(size 1.016 1.016)
					(thickness 0.1524)
				)
				(justify mirror)
			)
		)
		(duplicate_pad_numbers_are_jumpers no)
		(fp_poly
			(pts
				(arc
					(start 0.4064 0)
					(mid -0.4064 0)
					(end 0.4064 0)
				)
			)
			(stroke
				(width 0)
				(type default)
			)
			(fill no)
			(layer "B.CrtYd")
		)
		(fp_poly
			(pts
				(arc
					(start 0.7112 0)
					(mid -0.7112 0)
					(end 0.7112 0)
				)
			)
			(stroke
				(width 0)
				(type default)
			)
			(fill no)
			(layer "B.Fab")
		)
		(pad "1" smd circle
			(at 0 0 180)
			(size 0.8128 0.8128)
			(layers "B.Cu" "B.Mask" "B.Paste")
			(net "REDV_PD#")
		)
	)
	(footprint ""
		(layer "B.Cu")
		(at 98.171 -91.9734)
		(property "Reference" "STP163"
			(at 0 0 0)
			(layer "B.SilkS")
			(hide yes)
			(effects
				(font
					(size 1.27 1.27)
				)
				(justify mirror)
			)
		)
		(property "Value" "TPAD28"
			(at -0.0127 -1.8034 0)
			(unlocked yes)
			(layer "B.Fab")
			(hide yes)
			(effects
				(font
					(size 1.016 1.016)
					(thickness 0.1524)
				)
				(justify mirror)
			)
		)
		(property "Device Type" "TPAD28"
			(at -0.0127 -3.3274 0)
			(unlocked yes)
			(layer "B.Fab")
			(hide yes)
			(effects
				(font
					(size 1.016 1.016)
					(thickness 0.1524)
				)
				(justify mirror)
			)
		)
		(duplicate_pad_numbers_are_jumpers no)
		(fp_poly
			(pts
				(arc
					(start 0.3556 0)
					(mid -0.3556 0)
					(end 0.3556 0)
				)
			)
			(stroke
				(width 0)
				(type default)
			)
			(fill no)
			(layer "B.CrtYd")
		)
		(fp_poly
			(pts
				(arc
					(start 0.6096 0)
					(mid -0.6096 0)
					(end 0.6096 0)
				)
			)
			(stroke
				(width 0)
				(type default)
			)
			(fill no)
			(layer "B.Fab")
		)
		(pad "1" smd circle
			(at 0 0 180)
			(size 0.7112 0.7112)
			(layers "B.Cu" "B.Mask" "B.Paste")
			(net "EXP_XM_ADDR_25")
		)
	)
	(footprint ""
		(layer "B.Cu")
		(at 111.29137 -98.1202 90)
		(property "Reference" "SC1254"
			(at 0 0 90)
			(layer "B.SilkS")
			(hide yes)
			(effects
				(font
					(size 1.27 1.27)
				)
				(justify mirror)
			)
		)
		(property "Value" "SCD1U6D3V1KX-GP"
			(at 2.8321 -1.7399 90)
			(unlocked yes)
			(layer "B.Fab")
			(hide yes)
			(effects
				(font
					(size 1.016 1.016)
					(thickness 0.1524)
				)
				(justify mirror)
			)
		)
		(property "Device Type" "C0201H13"
			(at 2.8321 -3.2639 90)
			(unlocked yes)
			(layer "B.Fab")
			(hide yes)
			(effects
				(font
					(size 1.016 1.016)
					(thickness 0.1524)
				)
				(justify mirror)
			)
		)
		(duplicate_pad_numbers_are_jumpers no)
		(fp_rect
			(start 0.2794 0.6477)
			(end -0.2794 -0.6477)
			(stroke
				(width 0)
				(type default)
			)
			(fill no)
			(layer "B.CrtYd")
		)
		(fp_rect
			(start 0.2794 0.6477)
			(end -0.2794 -0.6477)
			(stroke
				(width 0)
				(type default)
			)
			(fill no)
			(layer "B.Fab")
		)
		(pad "1" smd custom
			(at 0 -0.2794 270)
			(size 0.0762 0.0762)
			(layers "B.Cu" "B.Mask" "B.Paste")
			(net "P0V9_E")
			(options
				(clearance outline)
				(anchor circle)
			)
			(primitives
				(gr_poly
					(pts
						(arc
							(start 0.1524 0.127)
							(mid 0.137521 0.162921)
							(end 0.1016 0.1778)
						)
						(arc
							(start -0.1016 0.1778)
							(mid -0.137521 0.162921)
							(end -0.1524 0.127)
						)
						(arc
							(start -0.1524 -0.127)
							(mid -0.137521 -0.162921)
							(end -0.1016 -0.1778)
						)
						(arc
							(start 0.1016 -0.1778)
							(mid 0.137521 -0.162921)
							(end 0.1524 -0.127)
						)
					)
					(width 0)
					(fill yes)
				)
			)
		)
		(pad "2" smd custom
			(at 0 0.2794 270)
			(size 0.0762 0.0762)
			(layers "B.Cu" "B.Mask" "B.Paste")
			(net "GND")
			(options
				(clearance outline)
				(anchor circle)
			)
			(primitives
				(gr_poly
					(pts
						(arc
							(start 0.1524 0.127)
							(mid 0.137521 0.162921)
							(end 0.1016 0.1778)
						)
						(arc
							(start -0.1016 0.1778)
							(mid -0.137521 0.162921)
							(end -0.1524 0.127)
						)
						(arc
							(start -0.1524 -0.127)
							(mid -0.137521 -0.162921)
							(end -0.1016 -0.1778)
						)
						(arc
							(start 0.1016 -0.1778)
							(mid 0.137521 -0.162921)
							(end 0.1524 -0.127)
						)
					)
					(width 0)
					(fill yes)
				)
			)
		)
	)
	(footprint ""
		(layer "B.Cu")
		(at 103.359966 -48.26 90)
		(property "Reference" "SC1057"
			(at 0 0 90)
			(layer "B.SilkS")
			(hide yes)
			(effects
				(font
					(size 1.27 1.27)
				)
				(justify mirror)
			)
		)
		(property "Value" "SCD1U16V2KX-3GP"
			(at -1.1811 -2.7051 90)
			(unlocked yes)
			(layer "B.Fab")
			(hide yes)
			(effects
				(font
					(size 1.016 1.016)
					(thickness 0.1524)
				)
				(justify mirror)
			)
		)
		(property "Device Type" "C402H22"
			(at -1.1811 -4.2291 90)
			(unlocked yes)
			(layer "B.Fab")
			(hide yes)
			(effects
				(font
					(size 1.016 1.016)
					(thickness 0.1524)
				)
				(justify mirror)
			)
		)
		(duplicate_pad_numbers_are_jumpers no)
		(fp_rect
			(start 0.4318 0.9525)
			(end -0.4318 -0.9525)
			(stroke
				(width 0)
				(type default)
			)
			(fill no)
			(layer "B.CrtYd")
		)
		(fp_rect
			(start 0.4318 0.9525)
			(end -0.4318 -0.9525)
			(stroke
				(width 0)
				(type default)
			)
			(fill no)
			(layer "B.Fab")
		)
		(pad "1" smd custom
			(at 0 -0.4445 270)
			(size 0.1524 0.1524)
			(layers "B.Cu" "B.Mask" "B.Paste")
			(net "P0V955_C")
			(options
				(clearance outline)
				(anchor circle)
			)
			(primitives
				(gr_poly
					(pts
						(arc
							(start 0.3048 0.2032)
							(mid 0.275042 0.275042)
							(end 0.2032 0.3048)
						)
						(arc
							(start -0.2032 0.3048)
							(mid -0.275042 0.275042)
							(end -0.3048 0.2032)
						)
						(arc
							(start -0.3048 -0.2032)
							(mid -0.275042 -0.275042)
							(end -0.2032 -0.3048)
						)
						(arc
							(start 0.2032 -0.3048)
							(mid 0.275042 -0.275042)
							(end 0.3048 -0.2032)
						)
					)
					(width 0)
					(fill yes)
				)
			)
		)
		(pad "2" smd custom
			(at 0 0.4445 270)
			(size 0.1524 0.1524)
			(layers "B.Cu" "B.Mask" "B.Paste")
			(net "GND")
			(options
				(clearance outline)
				(anchor circle)
			)
			(primitives
				(gr_poly
					(pts
						(arc
							(start 0.3048 0.2032)
							(mid 0.275042 0.275042)
							(end 0.2032 0.3048)
						)
						(arc
							(start -0.2032 0.3048)
							(mid -0.275042 0.275042)
							(end -0.3048 0.2032)
						)
						(arc
							(start -0.3048 -0.2032)
							(mid -0.275042 -0.275042)
							(end -0.2032 -0.3048)
						)
						(arc
							(start 0.2032 -0.3048)
							(mid 0.275042 -0.275042)
							(end 0.3048 -0.2032)
						)
					)
					(width 0)
					(fill yes)
				)
			)
		)
	)
	(footprint ""
		(layer "B.Cu")
		(at 25.350216 -232.33888)
		(property "Reference" "R502"
			(at 0 0 0)
			(layer "B.SilkS")
			(hide yes)
			(effects
				(font
					(size 1.27 1.27)
				)
				(justify mirror)
			)
		)
		(property "Value" "0R2J-2-GP"
			(at -0.064008 -3.993896 0)
			(unlocked yes)
			(layer "B.Fab")
			(hide yes)
			(effects
				(font
					(size 1.016 1.016)
					(thickness 0.1524)
				)
				(justify mirror)
			)
		)
		(property "Device Type" "R402H16"
			(at -0.064008 -5.517896 0)
			(unlocked yes)
			(layer "B.Fab")
			(hide yes)
			(effects
				(font
					(size 1.016 1.016)
					(thickness 0.1524)
				)
				(justify mirror)
			)
		)
		(duplicate_pad_numbers_are_jumpers no)
		(fp_line
			(start -0.508 -0.9398)
			(end 0.508 -0.9398)
			(stroke
				(width 0.1524)
				(type default)
			)
			(layer "B.SilkS")
		)
		(fp_line
			(start 0.508 -0.9398)
			(end 0.508 0.9398)
			(stroke
				(width 0.1524)
				(type default)
			)
			(layer "B.SilkS")
		)
		(fp_rect
			(start 0.508 0.9398)
			(end -0.508 -0.9398)
			(stroke
				(width 0)
				(type default)
			)
			(fill no)
			(layer "B.CrtYd")
		)
		(fp_rect
			(start 0.508 0.9398)
			(end -0.508 -0.9398)
			(stroke
				(width 0)
				(type default)
			)
			(fill no)
			(layer "B.Fab")
		)
		(pad "1" smd custom
			(at 0 -0.4445 180)
			(size 0.1397 0.1397)
			(layers "B.Cu" "B.Mask" "B.Paste")
			(net "SAS_HDD_PWR0_PCIE")
			(options
				(clearance outline)
				(anchor circle)
			)
			(primitives
				(gr_poly
					(pts
						(arc
							(start -0.1778 0.2794)
							(mid -0.249642 0.249642)
							(end -0.2794 0.1778)
						)
						(arc
							(start -0.2794 -0.1778)
							(mid -0.249642 -0.249642)
							(end -0.1778 -0.2794)
						)
						(arc
							(start 0.1778 -0.2794)
							(mid 0.249642 -0.249642)
							(end 0.2794 -0.1778)
						)
						(arc
							(start 0.2794 0.1778)
							(mid 0.249642 0.249642)
							(end 0.1778 0.2794)
						)
					)
					(width 0)
					(fill yes)
				)
			)
		)
		(pad "2" smd custom
			(at 0 0.4445 180)
			(size 0.1397 0.1397)
			(layers "B.Cu" "B.Mask" "B.Paste")
			(net "SAS_HDD_PWR0")
			(options
				(clearance outline)
				(anchor circle)
			)
			(primitives
				(gr_poly
					(pts
						(arc
							(start -0.1778 0.2794)
							(mid -0.249642 0.249642)
							(end -0.2794 0.1778)
						)
						(arc
							(start -0.2794 -0.1778)
							(mid -0.249642 -0.249642)
							(end -0.1778 -0.2794)
						)
						(arc
							(start 0.1778 -0.2794)
							(mid 0.249642 -0.249642)
							(end 0.2794 -0.1778)
						)
						(arc
							(start 0.2794 0.1778)
							(mid 0.249642 0.249642)
							(end 0.1778 0.2794)
						)
					)
					(width 0)
					(fill yes)
				)
			)
		)
	)
	(footprint ""
		(layer "B.Cu")
		(at 103.359966 -46.609 90)
		(property "Reference" "SC1023"
			(at 0 0 90)
			(layer "B.SilkS")
			(hide yes)
			(effects
				(font
					(size 1.27 1.27)
				)
				(justify mirror)
			)
		)
		(property "Value" "SC1U10V2KX-4-GP"
			(at -1.1811 -2.7051 90)
			(unlocked yes)
			(layer "B.Fab")
			(hide yes)
			(effects
				(font
					(size 1.016 1.016)
					(thickness 0.1524)
				)
				(justify mirror)
			)
		)
		(property "Device Type" "C402H22"
			(at -1.1811 -4.2291 90)
			(unlocked yes)
			(layer "B.Fab")
			(hide yes)
			(effects
				(font
					(size 1.016 1.016)
					(thickness 0.1524)
				)
				(justify mirror)
			)
		)
		(duplicate_pad_numbers_are_jumpers no)
		(fp_rect
			(start 0.4318 0.9525)
			(end -0.4318 -0.9525)
			(stroke
				(width 0)
				(type default)
			)
			(fill no)
			(layer "B.CrtYd")
		)
		(fp_rect
			(start 0.4318 0.9525)
			(end -0.4318 -0.9525)
			(stroke
				(width 0)
				(type default)
			)
			(fill no)
			(layer "B.Fab")
		)
		(pad "1" smd custom
			(at 0 -0.4445 270)
			(size 0.1524 0.1524)
			(layers "B.Cu" "B.Mask" "B.Paste")
			(net "P0V955_C")
			(options
				(clearance outline)
				(anchor circle)
			)
			(primitives
				(gr_poly
					(pts
						(arc
							(start 0.3048 0.2032)
							(mid 0.275042 0.275042)
							(end 0.2032 0.3048)
						)
						(arc
							(start -0.2032 0.3048)
							(mid -0.275042 0.275042)
							(end -0.3048 0.2032)
						)
						(arc
							(start -0.3048 -0.2032)
							(mid -0.275042 -0.275042)
							(end -0.2032 -0.3048)
						)
						(arc
							(start 0.2032 -0.3048)
							(mid 0.275042 -0.275042)
							(end 0.3048 -0.2032)
						)
					)
					(width 0)
					(fill yes)
				)
			)
		)
		(pad "2" smd custom
			(at 0 0.4445 270)
			(size 0.1524 0.1524)
			(layers "B.Cu" "B.Mask" "B.Paste")
			(net "GND")
			(options
				(clearance outline)
				(anchor circle)
			)
			(primitives
				(gr_poly
					(pts
						(arc
							(start 0.3048 0.2032)
							(mid 0.275042 0.275042)
							(end 0.2032 0.3048)
						)
						(arc
							(start -0.2032 0.3048)
							(mid -0.275042 0.275042)
							(end -0.3048 0.2032)
						)
						(arc
							(start -0.3048 -0.2032)
							(mid -0.275042 -0.275042)
							(end -0.2032 -0.3048)
						)
						(arc
							(start 0.2032 -0.3048)
							(mid 0.275042 -0.275042)
							(end 0.3048 -0.2032)
						)
					)
					(width 0)
					(fill yes)
				)
			)
		)
	)
	(footprint ""
		(layer "B.Cu")
		(at 303.8094 -182.6514)
		(property "Reference" "TP103"
			(at 0 0 0)
			(layer "B.SilkS")
			(hide yes)
			(effects
				(font
					(size 1.27 1.27)
				)
				(justify mirror)
			)
		)
		(property "Value" "TPAD28"
			(at -0.0127 -1.8034 0)
			(unlocked yes)
			(layer "B.Fab")
			(hide yes)
			(effects
				(font
					(size 1.016 1.016)
					(thickness 0.1524)
				)
				(justify mirror)
			)
		)
		(property "Device Type" "TPAD28"
			(at -0.0127 -3.3274 0)
			(unlocked yes)
			(layer "B.Fab")
			(hide yes)
			(effects
				(font
					(size 1.016 1.016)
					(thickness 0.1524)
				)
				(justify mirror)
			)
		)
		(duplicate_pad_numbers_are_jumpers no)
		(fp_poly
			(pts
				(arc
					(start 0.3556 0)
					(mid -0.3556 0)
					(end 0.3556 0)
				)
			)
			(stroke
				(width 0)
				(type default)
			)
			(fill no)
			(layer "B.CrtYd")
		)
		(fp_poly
			(pts
				(arc
					(start 0.6096 0)
					(mid -0.6096 0)
					(end 0.6096 0)
				)
			)
			(stroke
				(width 0)
				(type default)
			)
			(fill no)
			(layer "B.Fab")
		)
		(pad "1" smd circle
			(at 0 0 180)
			(size 0.7112 0.7112)
			(layers "B.Cu" "B.Mask" "B.Paste")
			(net "TP_BMC_GPIOL4")
		)
	)
	(footprint ""
		(layer "B.Cu")
		(at 110.88116 -35.306 90)
		(property "Reference" "SC995"
			(at 0 0 90)
			(layer "B.SilkS")
			(hide yes)
			(effects
				(font
					(size 1.27 1.27)
				)
				(justify mirror)
			)
		)
		(property "Value" "SCD1U16V2KX-3GP"
			(at -1.1811 -2.7051 90)
			(unlocked yes)
			(layer "B.Fab")
			(hide yes)
			(effects
				(font
					(size 1.016 1.016)
					(thickness 0.1524)
				)
				(justify mirror)
			)
		)
		(property "Device Type" "C402H22"
			(at -1.1811 -4.2291 90)
			(unlocked yes)
			(layer "B.Fab")
			(hide yes)
			(effects
				(font
					(size 1.016 1.016)
					(thickness 0.1524)
				)
				(justify mirror)
			)
		)
		(duplicate_pad_numbers_are_jumpers no)
		(fp_rect
			(start 0.4318 0.9525)
			(end -0.4318 -0.9525)
			(stroke
				(width 0)
				(type default)
			)
			(fill no)
			(layer "B.CrtYd")
		)
		(fp_rect
			(start 0.4318 0.9525)
			(end -0.4318 -0.9525)
			(stroke
				(width 0)
				(type default)
			)
			(fill no)
			(layer "B.Fab")
		)
		(pad "1" smd custom
			(at 0 -0.4445 270)
			(size 0.1524 0.1524)
			(layers "B.Cu" "B.Mask" "B.Paste")
			(net "P1V8_C")
			(options
				(clearance outline)
				(anchor circle)
			)
			(primitives
				(gr_poly
					(pts
						(arc
							(start 0.3048 0.2032)
							(mid 0.275042 0.275042)
							(end 0.2032 0.3048)
						)
						(arc
							(start -0.2032 0.3048)
							(mid -0.275042 0.275042)
							(end -0.3048 0.2032)
						)
						(arc
							(start -0.3048 -0.2032)
							(mid -0.275042 -0.275042)
							(end -0.2032 -0.3048)
						)
						(arc
							(start 0.2032 -0.3048)
							(mid 0.275042 -0.275042)
							(end 0.3048 -0.2032)
						)
					)
					(width 0)
					(fill yes)
				)
			)
		)
		(pad "2" smd custom
			(at 0 0.4445 270)
			(size 0.1524 0.1524)
			(layers "B.Cu" "B.Mask" "B.Paste")
			(net "GND")
			(options
				(clearance outline)
				(anchor circle)
			)
			(primitives
				(gr_poly
					(pts
						(arc
							(start 0.3048 0.2032)
							(mid 0.275042 0.275042)
							(end 0.2032 0.3048)
						)
						(arc
							(start -0.2032 0.3048)
							(mid -0.275042 0.275042)
							(end -0.3048 0.2032)
						)
						(arc
							(start -0.3048 -0.2032)
							(mid -0.275042 -0.275042)
							(end -0.2032 -0.3048)
						)
						(arc
							(start 0.2032 -0.3048)
							(mid 0.275042 -0.275042)
							(end 0.3048 -0.2032)
						)
					)
					(width 0)
					(fill yes)
				)
			)
		)
	)
	(footprint ""
		(layer "B.Cu")
		(at 340.110318 -133.353048 90)
		(property "Reference" "R555"
			(at 0 0 90)
			(layer "B.SilkS")
			(hide yes)
			(effects
				(font
					(size 1.27 1.27)
				)
				(justify mirror)
			)
		)
		(property "Value" "0R3J-0-U-GP"
			(at 0.0254 -2.5146 90)
			(unlocked yes)
			(layer "B.Fab")
			(hide yes)
			(effects
				(font
					(size 1.016 1.016)
					(thickness 0.1524)
				)
				(justify mirror)
			)
		)
		(property "Device Type" "R603H22"
			(at 0.0254 -4.0386 90)
			(unlocked yes)
			(layer "B.Fab")
			(hide yes)
			(effects
				(font
					(size 1.016 1.016)
					(thickness 0.1524)
				)
				(justify mirror)
			)
		)
		(duplicate_pad_numbers_are_jumpers no)
		(fp_line
			(start 0.4826 0)
			(end 0.2032 0)
			(stroke
				(width 0.2032)
				(type default)
			)
			(layer "B.SilkS")
		)
		(fp_line
			(start -0.2032 0)
			(end -0.4826 0)
			(stroke
				(width 0.2032)
				(type default)
			)
			(layer "B.SilkS")
		)
		(fp_rect
			(start 0.5842 1.3335)
			(end -0.5842 -1.3335)
			(stroke
				(width 0)
				(type default)
			)
			(fill no)
			(layer "B.CrtYd")
		)
		(fp_rect
			(start 0.5842 1.3335)
			(end -0.5842 -1.3335)
			(stroke
				(width 0)
				(type default)
			)
			(fill no)
			(layer "B.Fab")
		)
		(pad "1" smd custom
			(at 0 -0.762 270)
			(size 0.2159 0.2159)
			(layers "B.Cu" "B.Mask" "B.Paste")
			(net "USB_P0_DP")
			(options
				(clearance outline)
				(anchor circle)
			)
			(primitives
				(gr_poly
					(pts
						(arc
							(start -0.3302 0.4318)
							(mid -0.402042 0.402042)
							(end -0.4318 0.3302)
						)
						(arc
							(start -0.4318 -0.3302)
							(mid -0.402042 -0.402042)
							(end -0.3302 -0.4318)
						)
						(arc
							(start 0.3302 -0.4318)
							(mid 0.402042 -0.402042)
							(end 0.4318 -0.3302)
						)
						(arc
							(start 0.4318 0.3302)
							(mid 0.402042 0.402042)
							(end 0.3302 0.4318)
						)
					)
					(width 0)
					(fill yes)
				)
			)
		)
		(pad "2" smd custom
			(at 0 0.762 270)
			(size 0.2159 0.2159)
			(layers "B.Cu" "B.Mask" "B.Paste")
			(net "USB_DP_R")
			(options
				(clearance outline)
				(anchor circle)
			)
			(primitives
				(gr_poly
					(pts
						(arc
							(start -0.3302 0.4318)
							(mid -0.402042 0.402042)
							(end -0.4318 0.3302)
						)
						(arc
							(start -0.4318 -0.3302)
							(mid -0.402042 -0.402042)
							(end -0.3302 -0.4318)
						)
						(arc
							(start 0.3302 -0.4318)
							(mid 0.402042 -0.402042)
							(end 0.4318 -0.3302)
						)
						(arc
							(start 0.4318 0.3302)
							(mid 0.402042 0.402042)
							(end 0.3302 0.4318)
						)
					)
					(width 0)
					(fill yes)
				)
			)
		)
	)
)
